# T6G (Grand Teton) — schematic netlist excerpt (pin names and nets, part order shuffled) for the footprints in the layout excerpt that follows; sources: Cadence DE-HDL packaged netlist, KiCad conversion of 04192023_DAF0TMB3IC0_F0TG_MB_C_brd_V02_OCP.brd

R3005  Q_RES  18K 1% CHIP  pkg 0402LF  page 257 : A = P5V ; B = P5V_ADC
R3526  Q_RES  0 5% CHIP  pkg 0402LF  page 250 : A = SMB_PCIE0_3V3AUX_SCL_R5 ; B = SMB_SENSOR_E1S_3V3AUX_SCL

(kicad_pcb
	(version 20260206)
	(generator "pcbnew")
	(generator_version "10.0")
	(general
		(thickness 1.6)
		(legacy_teardrops no)
	)
	(paper "A4")
	(title_block
		(title "04192023_DAF0TMB3IC0_F0TG_MB_C_brd_V02_OCP.brd")
		(comment 1 "Grand Teton / footprints 1471-1472 of 8354")
	)
	(layers
		(0 "F.Cu" signal "TOP")
		(4 "In1.Cu" signal "GND")
		(6 "In2.Cu" signal "IN1")
		(8 "In3.Cu" signal "GND1")
		(10 "In4.Cu" signal "IN2")
		(12 "In5.Cu" signal "GND2")
		(14 "In6.Cu" signal "IN3")
		(16 "In7.Cu" signal "GND3")
		(18 "In8.Cu" signal "VCC")
		(20 "In9.Cu" signal "VCC1")
		(22 "In10.Cu" signal "GND4")
		(24 "In11.Cu" signal "IN4")
		(26 "In12.Cu" signal "GND5")
		(28 "In13.Cu" signal "IN5")
		(30 "In14.Cu" signal "GND6")
		(32 "In15.Cu" signal "IN6")
		(34 "In16.Cu" signal "GND7")
		(2 "B.Cu" signal "BOTTOM")
		(9 "F.Adhes" user "F.Adhesive")
		(11 "B.Adhes" user "B.Adhesive")
		(13 "F.Paste" user "Package Geometry/Pastemask Top")
		(15 "B.Paste" user "Package Geometry/Pastemask Bottom")
		(5 "F.SilkS" user "Ref Des/Silkscreen Top")
		(7 "B.SilkS" user "Ref Des/Silkscreen Bottom")
		(1 "F.Mask" user "Board Geometry/Soldermask Top")
		(3 "B.Mask" user "Board Geometry/Soldermask Bottom")
		(17 "Dwgs.User" user "User.Drawings")
		(19 "Cmts.User" user "User.Comments")
		(21 "Eco1.User" user "User.Eco1")
		(23 "Eco2.User" user "User.Eco2")
		(25 "Edge.Cuts" user "Board Geometry/Outline")
		(27 "Margin" user)
		(31 "F.CrtYd" user "Package Geometry/Place Bound Top")
		(29 "B.CrtYd" user "Package Geometry/Place Bound Bottom")
		(35 "F.Fab" user "Ref Des/Assembly Top")
		(33 "B.Fab" user "Ref Des/Assembly Bottom")
	)
	(footprint ""
		(layer "F.Cu")
		(at 279.513792 -113.62817 180)
		(property "Reference" "R3526"
			(at 0 0 180)
			(layer "F.SilkS")
			(hide yes)
			(effects
				(font
					(size 1.27 1.27)
				)
			)
		)
		(property "Value" ""
			(at 0 0 180)
			(layer "F.Fab")
			(effects
				(font
					(size 1.27 1.27)
				)
			)
		)
		(duplicate_pad_numbers_are_jumpers no)
		(fp_line
			(start 0.7874 0.4064)
			(end -0.7874 0.4064)
			(stroke
				(width 0.1524)
				(type default)
			)
			(layer "F.SilkS")
		)
		(fp_line
			(start 0.7874 -0.4064)
			(end 0.7874 0.4064)
			(stroke
				(width 0.1524)
				(type default)
			)
			(layer "F.SilkS")
		)
		(fp_line
			(start -0.7874 0.4064)
			(end -0.7874 -0.4064)
			(stroke
				(width 0.1524)
				(type default)
			)
			(layer "F.SilkS")
		)
		(fp_line
			(start -0.7874 -0.4064)
			(end 0.7874 -0.4064)
			(stroke
				(width 0.1524)
				(type default)
			)
			(layer "F.SilkS")
		)
		(fp_line
			(start 0.67945 0.3048)
			(end 0.120396 0.3048)
			(stroke
				(width 0.1)
				(type default)
			)
			(layer "F.Fab")
		)
		(fp_line
			(start 0.67945 -0.3048)
			(end 0.67945 0.3048)
			(stroke
				(width 0.1)
				(type default)
			)
			(layer "F.Fab")
		)
		(fp_line
			(start 0.12065 -0.2794)
			(end 0.12065 -0.3048)
			(stroke
				(width 0.1)
				(type default)
			)
			(layer "F.Fab")
		)
		(fp_line
			(start 0.12065 -0.3048)
			(end 0.67945 -0.3048)
			(stroke
				(width 0.1)
				(type default)
			)
			(layer "F.Fab")
		)
		(fp_line
			(start 0.120396 0.3048)
			(end 0.120396 0.2794)
			(stroke
				(width 0.1)
				(type default)
			)
			(layer "F.Fab")
		)
		(fp_line
			(start 0.120396 0.2794)
			(end -0.12065 0.2794)
			(stroke
				(width 0.1)
				(type default)
			)
			(layer "F.Fab")
		)
		(fp_line
			(start -0.12065 0.3048)
			(end -0.67945 0.3048)
			(stroke
				(width 0.1)
				(type default)
			)
			(layer "F.Fab")
		)
		(fp_line
			(start -0.12065 0.2794)
			(end -0.12065 0.3048)
			(stroke
				(width 0.1)
				(type default)
			)
			(layer "F.Fab")
		)
		(fp_line
			(start -0.12065 -0.2794)
			(end 0.12065 -0.2794)
			(stroke
				(width 0.1)
				(type default)
			)
			(layer "F.Fab")
		)
		(fp_line
			(start -0.12065 -0.305054)
			(end -0.12065 -0.2794)
			(stroke
				(width 0.1)
				(type default)
			)
			(layer "F.Fab")
		)
		(fp_line
			(start -0.67945 0.3048)
			(end -0.67945 -0.305054)
			(stroke
				(width 0.1)
				(type default)
			)
			(layer "F.Fab")
		)
		(fp_line
			(start -0.67945 -0.305054)
			(end -0.12065 -0.305054)
			(stroke
				(width 0.1)
				(type default)
			)
			(layer "F.Fab")
		)
		(pad "1" smd circle
			(at -0.40005 0 180)
			(size 0 0)
			(layers "F.Cu" "F.Mask" "F.Paste")
			(net "SMB_PCIE0_3V3AUX_SCL_R5")
		)
		(pad "2" smd circle
			(at 0.40005 0 180)
			(size 0 0)
			(layers "F.Cu" "F.Mask" "F.Paste")
			(net "SMB_SENSOR_E1S_3V3AUX_SCL")
		)
	)
	(footprint ""
		(layer "F.Cu")
		(at 329.592178 -43.573954 180)
		(property "Reference" "R3005"
			(at 0 0 180)
			(layer "F.SilkS")
			(hide yes)
			(effects
				(font
					(size 1.27 1.27)
				)
			)
		)
		(property "Value" ""
			(at 0 0 180)
			(layer "F.Fab")
			(effects
				(font
					(size 1.27 1.27)
				)
			)
		)
		(duplicate_pad_numbers_are_jumpers no)
		(fp_line
			(start 0.7874 0.4064)
			(end -0.7874 0.4064)
			(stroke
				(width 0.1524)
				(type default)
			)
			(layer "F.SilkS")
		)
		(fp_line
			(start 0.7874 -0.4064)
			(end 0.7874 0.4064)
			(stroke
				(width 0.1524)
				(type default)
			)
			(layer "F.SilkS")
		)
		(fp_line
			(start -0.7874 0.4064)
			(end -0.7874 -0.4064)
			(stroke
				(width 0.1524)
				(type default)
			)
			(layer "F.SilkS")
		)
		(fp_line
			(start -0.7874 -0.4064)
			(end 0.7874 -0.4064)
			(stroke
				(width 0.1524)
				(type default)
			)
			(layer "F.SilkS")
		)
		(fp_line
			(start 0.67945 0.3048)
			(end 0.120396 0.3048)
			(stroke
				(width 0.1)
				(type default)
			)
			(layer "F.Fab")
		)
		(fp_line
			(start 0.67945 -0.3048)
			(end 0.67945 0.3048)
			(stroke
				(width 0.1)
				(type default)
			)
			(layer "F.Fab")
		)
		(fp_line
			(start 0.12065 -0.2794)
			(end 0.12065 -0.3048)
			(stroke
				(width 0.1)
				(type default)
			)
			(layer "F.Fab")
		)
		(fp_line
			(start 0.12065 -0.3048)
			(end 0.67945 -0.3048)
			(stroke
				(width 0.1)
				(type default)
			)
			(layer "F.Fab")
		)
		(fp_line
			(start 0.120396 0.3048)
			(end 0.120396 0.2794)
			(stroke
				(width 0.1)
				(type default)
			)
			(layer "F.Fab")
		)
		(fp_line
			(start 0.120396 0.2794)
			(end -0.12065 0.2794)
			(stroke
				(width 0.1)
				(type default)
			)
			(layer "F.Fab")
		)
		(fp_line
			(start -0.12065 0.3048)
			(end -0.67945 0.3048)
			(stroke
				(width 0.1)
				(type default)
			)
			(layer "F.Fab")
		)
		(fp_line
			(start -0.12065 0.2794)
			(end -0.12065 0.3048)
			(stroke
				(width 0.1)
				(type default)
			)
			(layer "F.Fab")
		)
		(fp_line
			(start -0.12065 -0.2794)
			(end 0.12065 -0.2794)
			(stroke
				(width 0.1)
				(type default)
			)
			(layer "F.Fab")
		)
		(fp_line
			(start -0.12065 -0.305054)
			(end -0.12065 -0.2794)
			(stroke
				(width 0.1)
				(type default)
			)
			(layer "F.Fab")
		)
		(fp_line
			(start -0.67945 0.3048)
			(end -0.67945 -0.305054)
			(stroke
				(width 0.1)
				(type default)
			)
			(layer "F.Fab")
		)
		(fp_line
			(start -0.67945 -0.305054)
			(end -0.12065 -0.305054)
			(stroke
				(width 0.1)
				(type default)
			)
			(layer "F.Fab")
		)
		(pad "1" smd circle
			(at -0.40005 0 180)
			(size 0 0)
			(layers "F.Cu" "F.Mask" "F.Paste")
			(net "P5V")
		)
		(pad "2" smd circle
			(at 0.40005 0 180)
			(size 0 0)
			(layers "F.Cu" "F.Mask" "F.Paste")
			(net "P5V_ADC")
		)
	)
)
